# S9S_MB_2U (Grand Teton) — schematic netlist excerpt (pin names and nets, part order shuffled) for the footprints in the layout excerpt that follows; sources: Cadence DE-HDL packaged netlist, KiCad conversion of 03242023_DA0F0TMBIJ0_F0T_Motherboard_J_brd_V01_OCP.brd

R3712  Q_RES  33.2 1% CHIP  pkg 0402LF  page 233 : A = SMB_VR_SENSOR_3V3AUX_SDA ; B = SMB_VR_SENSOR_3V3AUX_SDA_R
R4582  Q_RES  10K 1% EMPTY  pkg 0402LF  page 195 : A = P3V3_AUX ; B = FM_BOARD_BMC_SKU_ID1

(kicad_pcb
	(version 20260206)
	(generator "pcbnew")
	(generator_version "10.0")
	(general
		(thickness 1.6)
		(legacy_teardrops no)
	)
	(paper "A4")
	(title_block
		(title "03242023_DA0F0TMBIJ0_F0T_Motherboard_J_brd_V01_OCP.brd")
		(comment 1 "Grand Teton / footprints 1059-1060 of 6105")
	)
	(layers
		(0 "F.Cu" signal "TOP")
		(4 "In1.Cu" signal "GND")
		(6 "In2.Cu" signal "IN1")
		(8 "In3.Cu" signal "GND1")
		(10 "In4.Cu" signal "IN2")
		(12 "In5.Cu" signal "GND2")
		(14 "In6.Cu" signal "IN3")
		(16 "In7.Cu" signal "GND3")
		(18 "In8.Cu" signal "VCC")
		(20 "In9.Cu" signal "VCC1")
		(22 "In10.Cu" signal "GND4")
		(24 "In11.Cu" signal "IN4")
		(26 "In12.Cu" signal "GND5")
		(28 "In13.Cu" signal "IN5")
		(30 "In14.Cu" signal "GND6")
		(32 "In15.Cu" signal "IN6")
		(34 "In16.Cu" signal "GND7")
		(2 "B.Cu" signal "BOTTOM")
		(9 "F.Adhes" user "F.Adhesive")
		(11 "B.Adhes" user "B.Adhesive")
		(13 "F.Paste" user "Package Geometry/Pastemask Top")
		(15 "B.Paste" user "Package Geometry/Pastemask Bottom")
		(5 "F.SilkS" user "Ref Des/Silkscreen Top")
		(7 "B.SilkS" user "Ref Des/Silkscreen Bottom")
		(1 "F.Mask" user "Board Geometry/Soldermask Top")
		(3 "B.Mask" user "Board Geometry/Soldermask Bottom")
		(17 "Dwgs.User" user "User.Drawings")
		(19 "Cmts.User" user "User.Comments")
		(21 "Eco1.User" user "User.Eco1")
		(23 "Eco2.User" user "User.Eco2")
		(25 "Edge.Cuts" user "Board Geometry/Outline")
		(27 "Margin" user)
		(31 "F.CrtYd" user "Package Geometry/Place Bound Top")
		(29 "B.CrtYd" user "Package Geometry/Place Bound Bottom")
		(35 "F.Fab" user "Ref Des/Assembly Top")
		(33 "B.Fab" user "Ref Des/Assembly Bottom")
	)
	(footprint ""
		(layer "F.Cu")
		(at 68.085716 -114.74069 180)
		(property "Reference" "R3712"
			(at 0 0 180)
			(layer "F.SilkS")
			(hide yes)
			(effects
				(font
					(size 1.27 1.27)
				)
			)
		)
		(property "Value" ""
			(at 0 0 180)
			(layer "F.Fab")
			(effects
				(font
					(size 1.27 1.27)
				)
			)
		)
		(duplicate_pad_numbers_are_jumpers no)
		(fp_line
			(start 0.7874 0.4064)
			(end -0.7874 0.4064)
			(stroke
				(width 0.1524)
				(type default)
			)
			(layer "F.SilkS")
		)
		(fp_line
			(start 0.7874 -0.4064)
			(end 0.7874 0.4064)
			(stroke
				(width 0.1524)
				(type default)
			)
			(layer "F.SilkS")
		)
		(fp_line
			(start -0.7874 0.4064)
			(end -0.7874 -0.4064)
			(stroke
				(width 0.1524)
				(type default)
			)
			(layer "F.SilkS")
		)
		(fp_line
			(start -0.7874 -0.4064)
			(end 0.7874 -0.4064)
			(stroke
				(width 0.1524)
				(type default)
			)
			(layer "F.SilkS")
		)
		(fp_line
			(start 0.67945 0.3048)
			(end 0.120396 0.3048)
			(stroke
				(width 0.1)
				(type default)
			)
			(layer "F.Fab")
		)
		(fp_line
			(start 0.67945 -0.3048)
			(end 0.67945 0.3048)
			(stroke
				(width 0.1)
				(type default)
			)
			(layer "F.Fab")
		)
		(fp_line
			(start 0.12065 -0.2794)
			(end 0.12065 -0.3048)
			(stroke
				(width 0.1)
				(type default)
			)
			(layer "F.Fab")
		)
		(fp_line
			(start 0.12065 -0.3048)
			(end 0.67945 -0.3048)
			(stroke
				(width 0.1)
				(type default)
			)
			(layer "F.Fab")
		)
		(fp_line
			(start 0.120396 0.3048)
			(end 0.120396 0.2794)
			(stroke
				(width 0.1)
				(type default)
			)
			(layer "F.Fab")
		)
		(fp_line
			(start 0.120396 0.2794)
			(end -0.12065 0.2794)
			(stroke
				(width 0.1)
				(type default)
			)
			(layer "F.Fab")
		)
		(fp_line
			(start -0.12065 0.3048)
			(end -0.67945 0.3048)
			(stroke
				(width 0.1)
				(type default)
			)
			(layer "F.Fab")
		)
		(fp_line
			(start -0.12065 0.2794)
			(end -0.12065 0.3048)
			(stroke
				(width 0.1)
				(type default)
			)
			(layer "F.Fab")
		)
		(fp_line
			(start -0.12065 -0.2794)
			(end 0.12065 -0.2794)
			(stroke
				(width 0.1)
				(type default)
			)
			(layer "F.Fab")
		)
		(fp_line
			(start -0.12065 -0.305054)
			(end -0.12065 -0.2794)
			(stroke
				(width 0.1)
				(type default)
			)
			(layer "F.Fab")
		)
		(fp_line
			(start -0.67945 0.3048)
			(end -0.67945 -0.305054)
			(stroke
				(width 0.1)
				(type default)
			)
			(layer "F.Fab")
		)
		(fp_line
			(start -0.67945 -0.305054)
			(end -0.12065 -0.305054)
			(stroke
				(width 0.1)
				(type default)
			)
			(layer "F.Fab")
		)
		(pad "1" smd circle
			(at -0.40005 0 180)
			(size 0 0)
			(layers "F.Cu" "F.Mask" "F.Paste")
			(net "SMB_VR_SENSOR_3V3AUX_SDA")
		)
		(pad "2" smd circle
			(at 0.40005 0 180)
			(size 0 0)
			(layers "F.Cu" "F.Mask" "F.Paste")
			(net "SMB_VR_SENSOR_3V3AUX_SDA_R")
		)
	)
	(footprint ""
		(layer "F.Cu")
		(at 175.4124 -93.538548 90)
		(property "Reference" "R4582"
			(at 0 0 90)
			(layer "F.SilkS")
			(hide yes)
			(effects
				(font
					(size 1.27 1.27)
				)
			)
		)
		(property "Value" ""
			(at 0 0 90)
			(layer "F.Fab")
			(effects
				(font
					(size 1.27 1.27)
				)
			)
		)
		(duplicate_pad_numbers_are_jumpers no)
		(fp_line
			(start 0.7874 -0.4064)
			(end 0.7874 0.4064)
			(stroke
				(width 0.1524)
				(type default)
			)
			(layer "F.SilkS")
		)
		(fp_line
			(start -0.7874 -0.4064)
			(end 0.7874 -0.4064)
			(stroke
				(width 0.1524)
				(type default)
			)
			(layer "F.SilkS")
		)
		(fp_line
			(start 0.7874 0.4064)
			(end -0.7874 0.4064)
			(stroke
				(width 0.1524)
				(type default)
			)
			(layer "F.SilkS")
		)
		(fp_line
			(start -0.7874 0.4064)
			(end -0.7874 -0.4064)
			(stroke
				(width 0.1524)
				(type default)
			)
			(layer "F.SilkS")
		)
		(fp_line
			(start -0.12065 -0.305054)
			(end -0.12065 -0.2794)
			(stroke
				(width 0.1)
				(type default)
			)
			(layer "F.Fab")
		)
		(fp_line
			(start -0.67945 -0.305054)
			(end -0.12065 -0.305054)
			(stroke
				(width 0.1)
				(type default)
			)
			(layer "F.Fab")
		)
		(fp_line
			(start 0.67945 -0.3048)
			(end 0.67945 0.3048)
			(stroke
				(width 0.1)
				(type default)
			)
			(layer "F.Fab")
		)
		(fp_line
			(start 0.12065 -0.3048)
			(end 0.67945 -0.3048)
			(stroke
				(width 0.1)
				(type default)
			)
			(layer "F.Fab")
		)
		(fp_line
			(start 0.12065 -0.2794)
			(end 0.12065 -0.3048)
			(stroke
				(width 0.1)
				(type default)
			)
			(layer "F.Fab")
		)
		(fp_line
			(start -0.12065 -0.2794)
			(end 0.12065 -0.2794)
			(stroke
				(width 0.1)
				(type default)
			)
			(layer "F.Fab")
		)
		(fp_line
			(start 0.120396 0.2794)
			(end -0.12065 0.2794)
			(stroke
				(width 0.1)
				(type default)
			)
			(layer "F.Fab")
		)
		(fp_line
			(start -0.12065 0.2794)
			(end -0.12065 0.3048)
			(stroke
				(width 0.1)
				(type default)
			)
			(layer "F.Fab")
		)
		(fp_line
			(start 0.67945 0.3048)
			(end 0.120396 0.3048)
			(stroke
				(width 0.1)
				(type default)
			)
			(layer "F.Fab")
		)
		(fp_line
			(start 0.120396 0.3048)
			(end 0.120396 0.2794)
			(stroke
				(width 0.1)
				(type default)
			)
			(layer "F.Fab")
		)
		(fp_line
			(start -0.12065 0.3048)
			(end -0.67945 0.3048)
			(stroke
				(width 0.1)
				(type default)
			)
			(layer "F.Fab")
		)
		(fp_line
			(start -0.67945 0.3048)
			(end -0.67945 -0.305054)
			(stroke
				(width 0.1)
				(type default)
			)
			(layer "F.Fab")
		)
		(pad "1" smd rect
			(at -0.40005 0 270)
			(size 0.4572 0.508)
			(layers "F.Cu" "F.Mask" "F.Paste")
			(net "P3V3_AUX")
		)
		(pad "2" smd rect
			(at 0.40005 0 270)
			(size 0.4572 0.508)
			(layers "F.Cu" "F.Mask" "F.Paste")
			(net "FM_BOARD_BMC_SKU_ID1")
		)
	)
)
